# T6G (Grand Teton) — schematic netlist excerpt (pin names and nets, part order shuffled) for the footprints in the layout excerpt that follows; sources: Cadence DE-HDL packaged netlist, KiCad conversion of 04192023_DAF0TMB3IC0_F0TG_MB_C_brd_V02_OCP.brd

PC6001  Q_CAP  0.1UF 25V 10% X6S  pkg C0402  page 209 : A = P12V_AUX ; B = GND
C90  Q_CAP  0.1UF 25V 10% X7R  pkg 0402  page 183 : A = P3V3_9ZXL045_P1_VDD ; B = GND

(kicad_pcb
	(version 20260206)
	(generator "pcbnew")
	(generator_version "10.0")
	(general
		(thickness 1.6)
		(legacy_teardrops no)
	)
	(paper "A4")
	(title_block
		(title "04192023_DAF0TMB3IC0_F0TG_MB_C_brd_V02_OCP.brd")
		(comment 1 "Grand Teton / footprints 2744-2745 of 8354")
	)
	(layers
		(0 "F.Cu" signal "TOP")
		(4 "In1.Cu" signal "GND")
		(6 "In2.Cu" signal "IN1")
		(8 "In3.Cu" signal "GND1")
		(10 "In4.Cu" signal "IN2")
		(12 "In5.Cu" signal "GND2")
		(14 "In6.Cu" signal "IN3")
		(16 "In7.Cu" signal "GND3")
		(18 "In8.Cu" signal "VCC")
		(20 "In9.Cu" signal "VCC1")
		(22 "In10.Cu" signal "GND4")
		(24 "In11.Cu" signal "IN4")
		(26 "In12.Cu" signal "GND5")
		(28 "In13.Cu" signal "IN5")
		(30 "In14.Cu" signal "GND6")
		(32 "In15.Cu" signal "IN6")
		(34 "In16.Cu" signal "GND7")
		(2 "B.Cu" signal "BOTTOM")
		(9 "F.Adhes" user "F.Adhesive")
		(11 "B.Adhes" user "B.Adhesive")
		(13 "F.Paste" user "Package Geometry/Pastemask Top")
		(15 "B.Paste" user "Package Geometry/Pastemask Bottom")
		(5 "F.SilkS" user "Ref Des/Silkscreen Top")
		(7 "B.SilkS" user "Ref Des/Silkscreen Bottom")
		(1 "F.Mask" user "Board Geometry/Soldermask Top")
		(3 "B.Mask" user "Board Geometry/Soldermask Bottom")
		(17 "Dwgs.User" user "User.Drawings")
		(19 "Cmts.User" user "User.Comments")
		(21 "Eco1.User" user "User.Eco1")
		(23 "Eco2.User" user "User.Eco2")
		(25 "Edge.Cuts" user "Board Geometry/Outline")
		(27 "Margin" user)
		(31 "F.CrtYd" user "Package Geometry/Place Bound Top")
		(29 "B.CrtYd" user "Package Geometry/Place Bound Bottom")
		(35 "F.Fab" user "Ref Des/Assembly Top")
		(33 "B.Fab" user "Ref Des/Assembly Bottom")
	)
	(footprint ""
		(layer "F.Cu")
		(at 330.365354 -133.964172 180)
		(property "Reference" "PC6001"
			(at 0 0 180)
			(layer "F.SilkS")
			(hide yes)
			(effects
				(font
					(size 1.27 1.27)
				)
			)
		)
		(property "Value" ""
			(at 0 0 180)
			(layer "F.Fab")
			(effects
				(font
					(size 1.27 1.27)
				)
			)
		)
		(duplicate_pad_numbers_are_jumpers no)
		(fp_line
			(start 0.7874 0.4064)
			(end -0.7874 0.4064)
			(stroke
				(width 0.1524)
				(type default)
			)
			(layer "F.SilkS")
		)
		(fp_line
			(start 0.7874 -0.4064)
			(end 0.7874 0.4064)
			(stroke
				(width 0.1524)
				(type default)
			)
			(layer "F.SilkS")
		)
		(fp_line
			(start -0.7874 0.4064)
			(end -0.7874 -0.4064)
			(stroke
				(width 0.1524)
				(type default)
			)
			(layer "F.SilkS")
		)
		(fp_line
			(start -0.7874 -0.4064)
			(end 0.7874 -0.4064)
			(stroke
				(width 0.1524)
				(type default)
			)
			(layer "F.SilkS")
		)
		(fp_line
			(start 0.67945 0.3048)
			(end 0.120396 0.3048)
			(stroke
				(width 0.1)
				(type default)
			)
			(layer "F.Fab")
		)
		(fp_line
			(start 0.67945 -0.3048)
			(end 0.67945 0.3048)
			(stroke
				(width 0.1)
				(type default)
			)
			(layer "F.Fab")
		)
		(fp_line
			(start 0.12065 -0.2794)
			(end 0.12065 -0.3048)
			(stroke
				(width 0.1)
				(type default)
			)
			(layer "F.Fab")
		)
		(fp_line
			(start 0.12065 -0.3048)
			(end 0.67945 -0.3048)
			(stroke
				(width 0.1)
				(type default)
			)
			(layer "F.Fab")
		)
		(fp_line
			(start 0.120396 0.3048)
			(end 0.120396 0.2794)
			(stroke
				(width 0.1)
				(type default)
			)
			(layer "F.Fab")
		)
		(fp_line
			(start 0.120396 0.2794)
			(end -0.12065 0.2794)
			(stroke
				(width 0.1)
				(type default)
			)
			(layer "F.Fab")
		)
		(fp_line
			(start -0.12065 0.3048)
			(end -0.67945 0.3048)
			(stroke
				(width 0.1)
				(type default)
			)
			(layer "F.Fab")
		)
		(fp_line
			(start -0.12065 0.2794)
			(end -0.12065 0.3048)
			(stroke
				(width 0.1)
				(type default)
			)
			(layer "F.Fab")
		)
		(fp_line
			(start -0.12065 -0.2794)
			(end 0.12065 -0.2794)
			(stroke
				(width 0.1)
				(type default)
			)
			(layer "F.Fab")
		)
		(fp_line
			(start -0.12065 -0.305054)
			(end -0.12065 -0.2794)
			(stroke
				(width 0.1)
				(type default)
			)
			(layer "F.Fab")
		)
		(fp_line
			(start -0.67945 0.3048)
			(end -0.67945 -0.305054)
			(stroke
				(width 0.1)
				(type default)
			)
			(layer "F.Fab")
		)
		(fp_line
			(start -0.67945 -0.305054)
			(end -0.12065 -0.305054)
			(stroke
				(width 0.1)
				(type default)
			)
			(layer "F.Fab")
		)
		(pad "1" smd circle
			(at -0.40005 0 180)
			(size 0 0)
			(layers "F.Cu" "F.Mask" "F.Paste")
			(net "P12V_AUX")
		)
		(pad "2" smd circle
			(at 0.40005 0 180)
			(size 0 0)
			(layers "F.Cu" "F.Mask" "F.Paste")
			(net "GND")
		)
	)
	(footprint ""
		(layer "F.Cu")
		(at 100.48367 -408.183588 180)
		(property "Reference" "C90"
			(at 0 0 180)
			(layer "F.SilkS")
			(hide yes)
			(effects
				(font
					(size 1.27 1.27)
				)
			)
		)
		(property "Value" ""
			(at 0 0 180)
			(layer "F.Fab")
			(effects
				(font
					(size 1.27 1.27)
				)
			)
		)
		(duplicate_pad_numbers_are_jumpers no)
		(fp_line
			(start 0.7874 0.4064)
			(end -0.7874 0.4064)
			(stroke
				(width 0.1524)
				(type default)
			)
			(layer "F.SilkS")
		)
		(fp_line
			(start 0.7874 -0.4064)
			(end 0.7874 0.4064)
			(stroke
				(width 0.1524)
				(type default)
			)
			(layer "F.SilkS")
		)
		(fp_line
			(start -0.7874 0.4064)
			(end -0.7874 -0.4064)
			(stroke
				(width 0.1524)
				(type default)
			)
			(layer "F.SilkS")
		)
		(fp_line
			(start -0.7874 -0.4064)
			(end 0.7874 -0.4064)
			(stroke
				(width 0.1524)
				(type default)
			)
			(layer "F.SilkS")
		)
		(fp_line
			(start 0.67945 0.3048)
			(end 0.120396 0.3048)
			(stroke
				(width 0.1)
				(type default)
			)
			(layer "F.Fab")
		)
		(fp_line
			(start 0.67945 -0.3048)
			(end 0.67945 0.3048)
			(stroke
				(width 0.1)
				(type default)
			)
			(layer "F.Fab")
		)
		(fp_line
			(start 0.12065 -0.2794)
			(end 0.12065 -0.3048)
			(stroke
				(width 0.1)
				(type default)
			)
			(layer "F.Fab")
		)
		(fp_line
			(start 0.12065 -0.3048)
			(end 0.67945 -0.3048)
			(stroke
				(width 0.1)
				(type default)
			)
			(layer "F.Fab")
		)
		(fp_line
			(start 0.120396 0.3048)
			(end 0.120396 0.2794)
			(stroke
				(width 0.1)
				(type default)
			)
			(layer "F.Fab")
		)
		(fp_line
			(start 0.120396 0.2794)
			(end -0.12065 0.2794)
			(stroke
				(width 0.1)
				(type default)
			)
			(layer "F.Fab")
		)
		(fp_line
			(start -0.12065 0.3048)
			(end -0.67945 0.3048)
			(stroke
				(width 0.1)
				(type default)
			)
			(layer "F.Fab")
		)
		(fp_line
			(start -0.12065 0.2794)
			(end -0.12065 0.3048)
			(stroke
				(width 0.1)
				(type default)
			)
			(layer "F.Fab")
		)
		(fp_line
			(start -0.12065 -0.2794)
			(end 0.12065 -0.2794)
			(stroke
				(width 0.1)
				(type default)
			)
			(layer "F.Fab")
		)
		(fp_line
			(start -0.12065 -0.305054)
			(end -0.12065 -0.2794)
			(stroke
				(width 0.1)
				(type default)
			)
			(layer "F.Fab")
		)
		(fp_line
			(start -0.67945 0.3048)
			(end -0.67945 -0.305054)
			(stroke
				(width 0.1)
				(type default)
			)
			(layer "F.Fab")
		)
		(fp_line
			(start -0.67945 -0.305054)
			(end -0.12065 -0.305054)
			(stroke
				(width 0.1)
				(type default)
			)
			(layer "F.Fab")
		)
		(pad "1" smd circle
			(at -0.40005 0 180)
			(size 0 0)
			(layers "F.Cu" "F.Mask" "F.Paste")
			(net "P3V3_9ZXL045_P1_VDD")
		)
		(pad "2" smd circle
			(at 0.40005 0 180)
			(size 0 0)
			(layers "F.Cu" "F.Mask" "F.Paste")
			(net "GND")
		)
	)
)
